# S9S_MB_2U (Grand Teton) — schematic netlist excerpt (pin names and nets, part order shuffled) for the footprints in the layout excerpt that follows; sources: Cadence DE-HDL packaged netlist, KiCad conversion of 03242023_DA0F0TMBIJ0_F0T_Motherboard_J_brd_V01_OCP.brd

J70  PICOPROBE_BXA  DELTA-L 4.0 EMPTY  pkg TRIANG_LAUNCH_3PXB  page 308
  \1_p\  = DELTA_L_85_5INCH_BOT_DN
  \2_n\  = DELTA_L_85_5INCH_BOT_DP
  \3_g\  = DELTA_L_GND_1

(kicad_pcb
	(version 20260206)
	(generator "pcbnew")
	(generator_version "10.0")
	(general
		(thickness 1.6)
		(legacy_teardrops no)
	)
	(paper "A4")
	(title_block
		(title "03242023_DA0F0TMBIJ0_F0T_Motherboard_J_brd_V01_OCP.brd")
		(comment 1 "Grand Teton / footprints 5931-5931 of 6105")
	)
	(layers
		(0 "F.Cu" signal "TOP")
		(4 "In1.Cu" signal "GND")
		(6 "In2.Cu" signal "IN1")
		(8 "In3.Cu" signal "GND1")
		(10 "In4.Cu" signal "IN2")
		(12 "In5.Cu" signal "GND2")
		(14 "In6.Cu" signal "IN3")
		(16 "In7.Cu" signal "GND3")
		(18 "In8.Cu" signal "VCC")
		(20 "In9.Cu" signal "VCC1")
		(22 "In10.Cu" signal "GND4")
		(24 "In11.Cu" signal "IN4")
		(26 "In12.Cu" signal "GND5")
		(28 "In13.Cu" signal "IN5")
		(30 "In14.Cu" signal "GND6")
		(32 "In15.Cu" signal "IN6")
		(34 "In16.Cu" signal "GND7")
		(2 "B.Cu" signal "BOTTOM")
		(9 "F.Adhes" user "F.Adhesive")
		(11 "B.Adhes" user "B.Adhesive")
		(13 "F.Paste" user "Package Geometry/Pastemask Top")
		(15 "B.Paste" user "Package Geometry/Pastemask Bottom")
		(5 "F.SilkS" user "Ref Des/Silkscreen Top")
		(7 "B.SilkS" user "Ref Des/Silkscreen Bottom")
		(1 "F.Mask" user "Board Geometry/Soldermask Top")
		(3 "B.Mask" user "Board Geometry/Soldermask Bottom")
		(17 "Dwgs.User" user "User.Drawings")
		(19 "Cmts.User" user "User.Comments")
		(21 "Eco1.User" user "User.Eco1")
		(23 "Eco2.User" user "User.Eco2")
		(25 "Edge.Cuts" user "Board Geometry/Outline")
		(27 "Margin" user)
		(31 "F.CrtYd" user "Package Geometry/Place Bound Top")
		(29 "B.CrtYd" user "Package Geometry/Place Bound Bottom")
		(35 "F.Fab" user "Ref Des/Assembly Top")
		(33 "B.Fab" user "Ref Des/Assembly Bottom")
	)
	(footprint ""
		(layer "B.Cu")
		(at 339.298534 -2.156206 180)
		(property "Reference" "J70"
			(at 4.248404 -1.165606 270)
			(unlocked yes)
			(layer "B.SilkS")
			(effects
				(font
					(size 0.7874 0.5842)
					(thickness 0.1524)
				)
				(justify left mirror)
			)
		)
		(property "Value" ""
			(at 0 0 0)
			(layer "B.Fab")
			(effects
				(font
					(size 1.27 1.27)
				)
				(justify mirror)
			)
		)
		(duplicate_pad_numbers_are_jumpers no)
		(fp_line
			(start 1.2192 2.1082)
			(end 1.2192 -2.1082)
			(stroke
				(width 0.1524)
				(type default)
			)
			(layer "B.SilkS")
		)
		(fp_line
			(start 1.2192 -2.1082)
			(end -1.2192 -2.1082)
			(stroke
				(width 0.1524)
				(type default)
			)
			(layer "B.SilkS")
		)
		(fp_line
			(start -1.2192 2.1082)
			(end 1.2192 2.1082)
			(stroke
				(width 0.1524)
				(type default)
			)
			(layer "B.SilkS")
		)
		(fp_line
			(start -1.2192 -2.1082)
			(end -1.2192 2.1082)
			(stroke
				(width 0.1524)
				(type default)
			)
			(layer "B.SilkS")
		)
		(pad "" np_thru_hole circle
			(at -3.4671 -1.27 90)
			(size 1.0414 1.0414)
			(drill 1.0414)
			(layers "*.Cu" "*.Mask")
			(clearance 0.381)
			(thermal_gap 0.381)
		)
		(pad "" np_thru_hole circle
			(at -3.4671 1.27 90)
			(size 1.0414 1.0414)
			(drill 1.0414)
			(layers "*.Cu" "*.Mask")
			(clearance 0.381)
			(thermal_gap 0.381)
		)
		(pad "" np_thru_hole circle
			(at 2.8829 -1.27 90)
			(size 1.0414 1.0414)
			(drill 1.0414)
			(layers "*.Cu" "*.Mask")
			(clearance 0.381)
			(thermal_gap 0.381)
		)
		(pad "" np_thru_hole circle
			(at 2.8829 1.27 90)
			(size 1.0414 1.0414)
			(drill 1.0414)
			(layers "*.Cu" "*.Mask")
			(clearance 0.381)
			(thermal_gap 0.381)
		)
		(pad "1" smd rect
			(at -0.8255 -0.249936 90)
			(size 0.3048 0.508)
			(layers "B.Cu" "B.Mask" "B.Paste")
			(net "DELTA_L_85_5INCH_BOT_DN")
		)
		(pad "2" smd rect
			(at -0.8255 0.249936 90)
			(size 0.3048 0.508)
			(layers "B.Cu" "B.Mask" "B.Paste")
			(net "DELTA_L_85_5INCH_BOT_DP")
		)
		(pad "3" smd circle
			(at 0 0)
			(size 0 0)
			(layers "B.Cu" "B.Mask" "B.Paste")
			(net "DELTA_L_GND_1")
		)
		(zone
			(layers "F.Cu" "B.Cu" "In1.Cu" "In2.Cu" "In3.Cu" "In4.Cu" "In5.Cu" "In6.Cu"
				"In7.Cu" "In8.Cu" "In9.Cu" "In10.Cu" "In11.Cu" "In12.Cu" "In13.Cu" "In14.Cu"
				"In15.Cu" "In16.Cu"
			)
			(hatch none 0.5)
			(connect_pads
				(clearance 0)
			)
			(min_thickness 0.25)
			(keepout
				(tracks not_allowed)
				(vias allowed)
				(pads allowed)
				(copperpour not_allowed)
				(footprints allowed)
			)
			(placement
				(enabled no)
				(sheetname "")
			)
			(fill
				(thermal_gap 0.5)
				(thermal_bridge_width 0.5)
				(island_removal_mode 0)
			)
			(polygon
				(pts
					(arc
						(start 337.342734 -3.426206)
						(mid 335.488534 -3.426206)
						(end 337.342734 -3.426206)
					)
				)
			)
		)
		(zone
			(layers "F.Cu" "B.Cu" "In1.Cu" "In2.Cu" "In3.Cu" "In4.Cu" "In5.Cu" "In6.Cu"
				"In7.Cu" "In8.Cu" "In9.Cu" "In10.Cu" "In11.Cu" "In12.Cu" "In13.Cu" "In14.Cu"
				"In15.Cu" "In16.Cu"
			)
			(hatch none 0.5)
			(connect_pads
				(clearance 0)
			)
			(min_thickness 0.25)
			(keepout
				(tracks not_allowed)
				(vias allowed)
				(pads allowed)
				(copperpour not_allowed)
				(footprints allowed)
			)
			(placement
				(enabled no)
				(sheetname "")
			)
			(fill
				(thermal_gap 0.5)
				(thermal_bridge_width 0.5)
				(island_removal_mode 0)
			)
			(polygon
				(pts
					(arc
						(start 337.342734 -0.886206)
						(mid 335.488534 -0.886206)
						(end 337.342734 -0.886206)
					)
				)
			)
		)
		(zone
			(layers "F.Cu" "B.Cu" "In1.Cu" "In2.Cu" "In3.Cu" "In4.Cu" "In5.Cu" "In6.Cu"
				"In7.Cu" "In8.Cu" "In9.Cu" "In10.Cu" "In11.Cu" "In12.Cu" "In13.Cu" "In14.Cu"
				"In15.Cu" "In16.Cu"
			)
			(hatch none 0.5)
			(connect_pads
				(clearance 0)
			)
			(min_thickness 0.25)
			(keepout
				(tracks not_allowed)
				(vias allowed)
				(pads allowed)
				(copperpour not_allowed)
				(footprints allowed)
			)
			(placement
				(enabled no)
				(sheetname "")
			)
			(fill
				(thermal_gap 0.5)
				(thermal_bridge_width 0.5)
				(island_removal_mode 0)
			)
			(polygon
				(pts
					(arc
						(start 343.692734 -3.426206)
						(mid 341.838534 -3.426206)
						(end 343.692734 -3.426206)
					)
				)
			)
		)
		(zone
			(layers "F.Cu" "B.Cu" "In1.Cu" "In2.Cu" "In3.Cu" "In4.Cu" "In5.Cu" "In6.Cu"
				"In7.Cu" "In8.Cu" "In9.Cu" "In10.Cu" "In11.Cu" "In12.Cu" "In13.Cu" "In14.Cu"
				"In15.Cu" "In16.Cu"
			)
			(hatch none 0.5)
			(connect_pads
				(clearance 0)
			)
			(min_thickness 0.25)
			(keepout
				(tracks not_allowed)
				(vias allowed)
				(pads allowed)
				(copperpour not_allowed)
				(footprints allowed)
			)
			(placement
				(enabled no)
				(sheetname "")
			)
			(fill
				(thermal_gap 0.5)
				(thermal_bridge_width 0.5)
				(island_removal_mode 0)
			)
			(polygon
				(pts
					(arc
						(start 343.692734 -0.886206)
						(mid 341.838534 -0.886206)
						(end 343.692734 -0.886206)
					)
				)
			)
		)
		(zone
			(layer "B.Cu")
			(hatch none 0.5)
			(connect_pads
				(clearance 0)
			)
			(min_thickness 0.25)
			(keepout
				(tracks not_allowed)
				(vias allowed)
				(pads allowed)
				(copperpour not_allowed)
				(footprints allowed)
			)
			(placement
				(enabled no)
				(sheetname "")
			)
			(fill
				(thermal_gap 0.5)
				(thermal_bridge_width 0.5)
				(island_removal_mode 0)
			)
			(polygon
				(pts
					(xy 340.416134 -1.607566) (xy 340.416134 -1.70307) (xy 339.819234 -1.70307) (xy 339.819234 -2.10947)
					(xy 340.416134 -2.10947) (xy 340.416134 -2.202942) (xy 339.819234 -2.202942) (xy 339.819234 -2.609342)
					(xy 340.416134 -2.609342) (xy 340.416134 -2.704846) (xy 339.717634 -2.704846) (xy 339.717634 -1.607566)
				)
			)
		)
	)
)
